(kicad_pcb
	(version 20260206)
	(generator "pcbnew")
	(generator_version "10.0")
	(general
		(thickness 1.6)
		(legacy_teardrops no)
	)
	(paper "A4")
	(title_block
		(title "12092022_DA0F0TMDCD0_F0T_Management_Board_D_brd_V3_OCP.brd")
		(comment 1 "Grand Teton / footprints 1047-1052 of 1440")
	)
	(layers
		(0 "F.Cu" signal "TOP")
		(4 "In1.Cu" signal "GND")
		(6 "In2.Cu" signal "IN1")
		(8 "In3.Cu" signal "GND1")
		(10 "In4.Cu" signal "IN2")
		(12 "In5.Cu" signal "VCC")
		(14 "In6.Cu" signal "VCC1")
		(16 "In7.Cu" signal "IN3")
		(18 "In8.Cu" signal "GND2")
		(20 "In9.Cu" signal "IN4")
		(22 "In10.Cu" signal "GND3")
		(2 "B.Cu" signal "BOTTOM")
		(9 "F.Adhes" user "F.Adhesive")
		(11 "B.Adhes" user "B.Adhesive")
		(13 "F.Paste" user "Package Geometry/Pastemask Top")
		(15 "B.Paste" user "Package Geometry/Pastemask Bottom")
		(5 "F.SilkS" user "Ref Des/Silkscreen Top")
		(7 "B.SilkS" user "Ref Des/Silkscreen Bottom")
		(1 "F.Mask" user "Board Geometry/Soldermask Top")
		(3 "B.Mask" user "Board Geometry/Soldermask Bottom")
		(17 "Dwgs.User" user "User.Drawings")
		(19 "Cmts.User" user "User.Comments")
		(21 "Eco1.User" user "User.Eco1")
		(23 "Eco2.User" user "User.Eco2")
		(25 "Edge.Cuts" user "Board Geometry/Outline")
		(27 "Margin" user)
		(31 "F.CrtYd" user "Package Geometry/Place Bound Top")
		(29 "B.CrtYd" user "Package Geometry/Place Bound Bottom")
		(35 "F.Fab" user "Ref Des/Assembly Top")
		(33 "B.Fab" user "Ref Des/Assembly Bottom")
	)
	(footprint ""
		(layer "B.Cu")
		(at 58.381646 -46.974252 180)
		(property "Reference" "C41"
			(at 0 0 0)
			(layer "B.SilkS")
			(hide yes)
			(effects
				(font
					(size 1.27 1.27)
				)
				(justify mirror)
			)
		)
		(property "Value" ""
			(at 0 0 0)
			(layer "B.Fab")
			(effects
				(font
					(size 1.27 1.27)
				)
				(justify mirror)
			)
		)
		(duplicate_pad_numbers_are_jumpers no)
		(fp_line
			(start 0.7874 0.4064)
			(end 0.7874 -0.4064)
			(stroke
				(width 0.1524)
				(type default)
			)
			(layer "B.SilkS")
		)
		(fp_line
			(start 0.7874 -0.4064)
			(end -0.7874 -0.4064)
			(stroke
				(width 0.1524)
				(type default)
			)
			(layer "B.SilkS")
		)
		(fp_line
			(start -0.7874 0.4064)
			(end 0.7874 0.4064)
			(stroke
				(width 0.1524)
				(type default)
			)
			(layer "B.SilkS")
		)
		(fp_line
			(start -0.7874 -0.4064)
			(end -0.7874 0.4064)
			(stroke
				(width 0.1524)
				(type default)
			)
			(layer "B.SilkS")
		)
		(fp_line
			(start 0.67945 0.3048)
			(end 0.67945 -0.305054)
			(stroke
				(width 0.1)
				(type default)
			)
			(layer "B.Fab")
		)
		(fp_line
			(start 0.67945 -0.305054)
			(end 0.12065 -0.305054)
			(stroke
				(width 0.1)
				(type default)
			)
			(layer "B.Fab")
		)
		(fp_line
			(start 0.12065 0.3048)
			(end 0.67945 0.3048)
			(stroke
				(width 0.1)
				(type default)
			)
			(layer "B.Fab")
		)
		(fp_line
			(start 0.12065 0.2794)
			(end 0.12065 0.3048)
			(stroke
				(width 0.1)
				(type default)
			)
			(layer "B.Fab")
		)
		(fp_line
			(start 0.12065 -0.2794)
			(end -0.12065 -0.2794)
			(stroke
				(width 0.1)
				(type default)
			)
			(layer "B.Fab")
		)
		(fp_line
			(start 0.12065 -0.305054)
			(end 0.12065 -0.2794)
			(stroke
				(width 0.1)
				(type default)
			)
			(layer "B.Fab")
		)
		(fp_line
			(start -0.120396 0.3048)
			(end -0.120396 0.2794)
			(stroke
				(width 0.1)
				(type default)
			)
			(layer "B.Fab")
		)
		(fp_line
			(start -0.120396 0.2794)
			(end 0.12065 0.2794)
			(stroke
				(width 0.1)
				(type default)
			)
			(layer "B.Fab")
		)
		(fp_line
			(start -0.12065 -0.2794)
			(end -0.12065 -0.3048)
			(stroke
				(width 0.1)
				(type default)
			)
			(layer "B.Fab")
		)
		(fp_line
			(start -0.12065 -0.3048)
			(end -0.67945 -0.3048)
			(stroke
				(width 0.1)
				(type default)
			)
			(layer "B.Fab")
		)
		(fp_line
			(start -0.67945 0.3048)
			(end -0.120396 0.3048)
			(stroke
				(width 0.1)
				(type default)
			)
			(layer "B.Fab")
		)
		(fp_line
			(start -0.67945 -0.3048)
			(end -0.67945 0.3048)
			(stroke
				(width 0.1)
				(type default)
			)
			(layer "B.Fab")
		)
		(pad "1" smd circle
			(at 0.40005 0)
			(size 0 0)
			(layers "B.Cu" "B.Mask" "B.Paste")
			(net "P1V8_BMC_USB2AV18")
		)
		(pad "2" smd circle
			(at -0.40005 0)
			(size 0 0)
			(layers "B.Cu" "B.Mask" "B.Paste")
			(net "GND")
		)
	)
	(footprint ""
		(layer "B.Cu")
		(at 50.858674 -71.824342 180)
		(property "Reference" "C307"
			(at 0 0 0)
			(layer "B.SilkS")
			(hide yes)
			(effects
				(font
					(size 1.27 1.27)
				)
				(justify mirror)
			)
		)
		(property "Value" ""
			(at 0 0 0)
			(layer "B.Fab")
			(effects
				(font
					(size 1.27 1.27)
				)
				(justify mirror)
			)
		)
		(duplicate_pad_numbers_are_jumpers no)
		(fp_line
			(start 0.7874 0.4064)
			(end 0.7874 -0.4064)
			(stroke
				(width 0.1524)
				(type default)
			)
			(layer "B.SilkS")
		)
		(fp_line
			(start 0.7874 -0.4064)
			(end -0.7874 -0.4064)
			(stroke
				(width 0.1524)
				(type default)
			)
			(layer "B.SilkS")
		)
		(fp_line
			(start -0.7874 0.4064)
			(end 0.7874 0.4064)
			(stroke
				(width 0.1524)
				(type default)
			)
			(layer "B.SilkS")
		)
		(fp_line
			(start -0.7874 -0.4064)
			(end -0.7874 0.4064)
			(stroke
				(width 0.1524)
				(type default)
			)
			(layer "B.SilkS")
		)
		(fp_line
			(start 0.67945 0.3048)
			(end 0.67945 -0.305054)
			(stroke
				(width 0.1)
				(type default)
			)
			(layer "B.Fab")
		)
		(fp_line
			(start 0.67945 -0.305054)
			(end 0.12065 -0.305054)
			(stroke
				(width 0.1)
				(type default)
			)
			(layer "B.Fab")
		)
		(fp_line
			(start 0.12065 0.3048)
			(end 0.67945 0.3048)
			(stroke
				(width 0.1)
				(type default)
			)
			(layer "B.Fab")
		)
		(fp_line
			(start 0.12065 0.2794)
			(end 0.12065 0.3048)
			(stroke
				(width 0.1)
				(type default)
			)
			(layer "B.Fab")
		)
		(fp_line
			(start 0.12065 -0.2794)
			(end -0.12065 -0.2794)
			(stroke
				(width 0.1)
				(type default)
			)
			(layer "B.Fab")
		)
		(fp_line
			(start 0.12065 -0.305054)
			(end 0.12065 -0.2794)
			(stroke
				(width 0.1)
				(type default)
			)
			(layer "B.Fab")
		)
		(fp_line
			(start -0.120396 0.3048)
			(end -0.120396 0.2794)
			(stroke
				(width 0.1)
				(type default)
			)
			(layer "B.Fab")
		)
		(fp_line
			(start -0.120396 0.2794)
			(end 0.12065 0.2794)
			(stroke
				(width 0.1)
				(type default)
			)
			(layer "B.Fab")
		)
		(fp_line
			(start -0.12065 -0.2794)
			(end -0.12065 -0.3048)
			(stroke
				(width 0.1)
				(type default)
			)
			(layer "B.Fab")
		)
		(fp_line
			(start -0.12065 -0.3048)
			(end -0.67945 -0.3048)
			(stroke
				(width 0.1)
				(type default)
			)
			(layer "B.Fab")
		)
		(fp_line
			(start -0.67945 0.3048)
			(end -0.120396 0.3048)
			(stroke
				(width 0.1)
				(type default)
			)
			(layer "B.Fab")
		)
		(fp_line
			(start -0.67945 -0.3048)
			(end -0.67945 0.3048)
			(stroke
				(width 0.1)
				(type default)
			)
			(layer "B.Fab")
		)
		(pad "1" smd circle
			(at 0.40005 0)
			(size 0 0)
			(layers "B.Cu" "B.Mask" "B.Paste")
			(net "P1V8_SENSOR")
		)
		(pad "2" smd circle
			(at -0.40005 0)
			(size 0 0)
			(layers "B.Cu" "B.Mask" "B.Paste")
			(net "GND")
		)
	)
	(footprint ""
		(layer "B.Cu")
		(at 37.867336 -48.9204 180)
		(property "Reference" "R429"
			(at 0 0 0)
			(layer "B.SilkS")
			(hide yes)
			(effects
				(font
					(size 1.27 1.27)
				)
				(justify mirror)
			)
		)
		(property "Value" ""
			(at 0 0 0)
			(layer "B.Fab")
			(effects
				(font
					(size 1.27 1.27)
				)
				(justify mirror)
			)
		)
		(duplicate_pad_numbers_are_jumpers no)
		(fp_line
			(start 0.7874 0.4064)
			(end 0.7874 -0.4064)
			(stroke
				(width 0.1524)
				(type default)
			)
			(layer "B.SilkS")
		)
		(fp_line
			(start 0.7874 -0.4064)
			(end -0.7874 -0.4064)
			(stroke
				(width 0.1524)
				(type default)
			)
			(layer "B.SilkS")
		)
		(fp_line
			(start -0.7874 0.4064)
			(end 0.7874 0.4064)
			(stroke
				(width 0.1524)
				(type default)
			)
			(layer "B.SilkS")
		)
		(fp_line
			(start -0.7874 -0.4064)
			(end -0.7874 0.4064)
			(stroke
				(width 0.1524)
				(type default)
			)
			(layer "B.SilkS")
		)
		(fp_line
			(start 0.67945 0.3048)
			(end 0.67945 -0.305054)
			(stroke
				(width 0.1)
				(type default)
			)
			(layer "B.Fab")
		)
		(fp_line
			(start 0.67945 -0.305054)
			(end 0.12065 -0.305054)
			(stroke
				(width 0.1)
				(type default)
			)
			(layer "B.Fab")
		)
		(fp_line
			(start 0.12065 0.3048)
			(end 0.67945 0.3048)
			(stroke
				(width 0.1)
				(type default)
			)
			(layer "B.Fab")
		)
		(fp_line
			(start 0.12065 0.2794)
			(end 0.12065 0.3048)
			(stroke
				(width 0.1)
				(type default)
			)
			(layer "B.Fab")
		)
		(fp_line
			(start 0.12065 -0.2794)
			(end -0.12065 -0.2794)
			(stroke
				(width 0.1)
				(type default)
			)
			(layer "B.Fab")
		)
		(fp_line
			(start 0.12065 -0.305054)
			(end 0.12065 -0.2794)
			(stroke
				(width 0.1)
				(type default)
			)
			(layer "B.Fab")
		)
		(fp_line
			(start -0.120396 0.3048)
			(end -0.120396 0.2794)
			(stroke
				(width 0.1)
				(type default)
			)
			(layer "B.Fab")
		)
		(fp_line
			(start -0.120396 0.2794)
			(end 0.12065 0.2794)
			(stroke
				(width 0.1)
				(type default)
			)
			(layer "B.Fab")
		)
		(fp_line
			(start -0.12065 -0.2794)
			(end -0.12065 -0.3048)
			(stroke
				(width 0.1)
				(type default)
			)
			(layer "B.Fab")
		)
		(fp_line
			(start -0.12065 -0.3048)
			(end -0.67945 -0.3048)
			(stroke
				(width 0.1)
				(type default)
			)
			(layer "B.Fab")
		)
		(fp_line
			(start -0.67945 0.3048)
			(end -0.120396 0.3048)
			(stroke
				(width 0.1)
				(type default)
			)
			(layer "B.Fab")
		)
		(fp_line
			(start -0.67945 -0.3048)
			(end -0.67945 0.3048)
			(stroke
				(width 0.1)
				(type default)
			)
			(layer "B.Fab")
		)
		(pad "1" smd circle
			(at 0.40005 0)
			(size 0 0)
			(layers "B.Cu" "B.Mask" "B.Paste")
			(net "P3V3_AUX")
		)
		(pad "2" smd circle
			(at -0.40005 0)
			(size 0 0)
			(layers "B.Cu" "B.Mask" "B.Paste")
			(net "SMB_BMC_MM14_SCL")
		)
	)
	(footprint ""
		(layer "B.Cu")
		(at 49.7967 -104.2035 180)
		(property "Reference" "R866"
			(at 0 0 0)
			(layer "B.SilkS")
			(hide yes)
			(effects
				(font
					(size 1.27 1.27)
				)
				(justify mirror)
			)
		)
		(property "Value" ""
			(at 0 0 0)
			(layer "B.Fab")
			(effects
				(font
					(size 1.27 1.27)
				)
				(justify mirror)
			)
		)
		(duplicate_pad_numbers_are_jumpers no)
		(fp_line
			(start 0.7874 0.4064)
			(end 0.7874 -0.4064)
			(stroke
				(width 0.1524)
				(type default)
			)
			(layer "B.SilkS")
		)
		(fp_line
			(start 0.7874 -0.4064)
			(end -0.7874 -0.4064)
			(stroke
				(width 0.1524)
				(type default)
			)
			(layer "B.SilkS")
		)
		(fp_line
			(start -0.7874 0.4064)
			(end 0.7874 0.4064)
			(stroke
				(width 0.1524)
				(type default)
			)
			(layer "B.SilkS")
		)
		(fp_line
			(start -0.7874 -0.4064)
			(end -0.7874 0.4064)
			(stroke
				(width 0.1524)
				(type default)
			)
			(layer "B.SilkS")
		)
		(fp_line
			(start 0.67945 0.3048)
			(end 0.67945 -0.305054)
			(stroke
				(width 0.1)
				(type default)
			)
			(layer "B.Fab")
		)
		(fp_line
			(start 0.67945 -0.305054)
			(end 0.12065 -0.305054)
			(stroke
				(width 0.1)
				(type default)
			)
			(layer "B.Fab")
		)
		(fp_line
			(start 0.12065 0.3048)
			(end 0.67945 0.3048)
			(stroke
				(width 0.1)
				(type default)
			)
			(layer "B.Fab")
		)
		(fp_line
			(start 0.12065 0.2794)
			(end 0.12065 0.3048)
			(stroke
				(width 0.1)
				(type default)
			)
			(layer "B.Fab")
		)
		(fp_line
			(start 0.12065 -0.2794)
			(end -0.12065 -0.2794)
			(stroke
				(width 0.1)
				(type default)
			)
			(layer "B.Fab")
		)
		(fp_line
			(start 0.12065 -0.305054)
			(end 0.12065 -0.2794)
			(stroke
				(width 0.1)
				(type default)
			)
			(layer "B.Fab")
		)
		(fp_line
			(start -0.120396 0.3048)
			(end -0.120396 0.2794)
			(stroke
				(width 0.1)
				(type default)
			)
			(layer "B.Fab")
		)
		(fp_line
			(start -0.120396 0.2794)
			(end 0.12065 0.2794)
			(stroke
				(width 0.1)
				(type default)
			)
			(layer "B.Fab")
		)
		(fp_line
			(start -0.12065 -0.2794)
			(end -0.12065 -0.3048)
			(stroke
				(width 0.1)
				(type default)
			)
			(layer "B.Fab")
		)
		(fp_line
			(start -0.12065 -0.3048)
			(end -0.67945 -0.3048)
			(stroke
				(width 0.1)
				(type default)
			)
			(layer "B.Fab")
		)
		(fp_line
			(start -0.67945 0.3048)
			(end -0.120396 0.3048)
			(stroke
				(width 0.1)
				(type default)
			)
			(layer "B.Fab")
		)
		(fp_line
			(start -0.67945 -0.3048)
			(end -0.67945 0.3048)
			(stroke
				(width 0.1)
				(type default)
			)
			(layer "B.Fab")
		)
		(pad "1" smd circle
			(at 0.40005 0)
			(size 0 0)
			(layers "B.Cu" "B.Mask" "B.Paste")
			(net "FM_BMC_BIOS_MUX_CS_SPI_R_SEL_0")
		)
		(pad "2" smd circle
			(at -0.40005 0)
			(size 0 0)
			(layers "B.Cu" "B.Mask" "B.Paste")
			(net "GND")
		)
	)
	(footprint ""
		(layer "B.Cu")
		(at 83.16722 -46.586394)
		(property "Reference" "R1"
			(at 0 0 0)
			(layer "B.SilkS")
			(hide yes)
			(effects
				(font
					(size 1.27 1.27)
				)
				(justify mirror)
			)
		)
		(property "Value" ""
			(at 0 0 0)
			(layer "B.Fab")
			(effects
				(font
					(size 1.27 1.27)
				)
				(justify mirror)
			)
		)
		(duplicate_pad_numbers_are_jumpers no)
		(fp_line
			(start -0.7874 -0.4064)
			(end -0.7874 0.4064)
			(stroke
				(width 0.1524)
				(type default)
			)
			(layer "B.SilkS")
		)
		(fp_line
			(start -0.7874 0.4064)
			(end 0.7874 0.4064)
			(stroke
				(width 0.1524)
				(type default)
			)
			(layer "B.SilkS")
		)
		(fp_line
			(start 0.7874 -0.4064)
			(end -0.7874 -0.4064)
			(stroke
				(width 0.1524)
				(type default)
			)
			(layer "B.SilkS")
		)
		(fp_line
			(start 0.7874 0.4064)
			(end 0.7874 -0.4064)
			(stroke
				(width 0.1524)
				(type default)
			)
			(layer "B.SilkS")
		)
		(fp_line
			(start -0.67945 -0.3048)
			(end -0.67945 0.3048)
			(stroke
				(width 0.1)
				(type default)
			)
			(layer "B.Fab")
		)
		(fp_line
			(start -0.67945 0.3048)
			(end -0.120396 0.3048)
			(stroke
				(width 0.1)
				(type default)
			)
			(layer "B.Fab")
		)
		(fp_line
			(start -0.12065 -0.3048)
			(end -0.67945 -0.3048)
			(stroke
				(width 0.1)
				(type default)
			)
			(layer "B.Fab")
		)
		(fp_line
			(start -0.12065 -0.2794)
			(end -0.12065 -0.3048)
			(stroke
				(width 0.1)
				(type default)
			)
			(layer "B.Fab")
		)
		(fp_line
			(start -0.120396 0.2794)
			(end 0.12065 0.2794)
			(stroke
				(width 0.1)
				(type default)
			)
			(layer "B.Fab")
		)
		(fp_line
			(start -0.120396 0.3048)
			(end -0.120396 0.2794)
			(stroke
				(width 0.1)
				(type default)
			)
			(layer "B.Fab")
		)
		(fp_line
			(start 0.12065 -0.305054)
			(end 0.12065 -0.2794)
			(stroke
				(width 0.1)
				(type default)
			)
			(layer "B.Fab")
		)
		(fp_line
			(start 0.12065 -0.2794)
			(end -0.12065 -0.2794)
			(stroke
				(width 0.1)
				(type default)
			)
			(layer "B.Fab")
		)
		(fp_line
			(start 0.12065 0.2794)
			(end 0.12065 0.3048)
			(stroke
				(width 0.1)
				(type default)
			)
			(layer "B.Fab")
		)
		(fp_line
			(start 0.12065 0.3048)
			(end 0.67945 0.3048)
			(stroke
				(width 0.1)
				(type default)
			)
			(layer "B.Fab")
		)
		(fp_line
			(start 0.67945 -0.305054)
			(end 0.12065 -0.305054)
			(stroke
				(width 0.1)
				(type default)
			)
			(layer "B.Fab")
		)
		(fp_line
			(start 0.67945 0.3048)
			(end 0.67945 -0.305054)
			(stroke
				(width 0.1)
				(type default)
			)
			(layer "B.Fab")
		)
		(pad "1" smd circle
			(at 0.40005 0 180)
			(size 0 0)
			(layers "B.Cu" "B.Mask" "B.Paste")
			(net "M_BMC_DDR4_BG1")
		)
		(pad "2" smd circle
			(at -0.40005 0 180)
			(size 0 0)
			(layers "B.Cu" "B.Mask" "B.Paste")
			(net "M_BMC_DDR4_MBG1")
		)
	)
	(footprint ""
		(layer "B.Cu")
		(at 68.299838 -40.87622 90)
		(property "Reference" "C63"
			(at 0 0 90)
			(layer "B.SilkS")
			(hide yes)
			(effects
				(font
					(size 1.27 1.27)
				)
				(justify mirror)
			)
		)
		(property "Value" ""
			(at 0 0 90)
			(layer "B.Fab")
			(effects
				(font
					(size 1.27 1.27)
				)
				(justify mirror)
			)
		)
		(duplicate_pad_numbers_are_jumpers no)
		(fp_line
			(start 0.7874 -0.4064)
			(end -0.7874 -0.4064)
			(stroke
				(width 0.1524)
				(type default)
			)
			(layer "B.SilkS")
		)
		(fp_line
			(start -0.7874 -0.4064)
			(end -0.7874 0.4064)
			(stroke
				(width 0.1524)
				(type default)
			)
			(layer "B.SilkS")
		)
		(fp_line
			(start 0.7874 0.4064)
			(end 0.7874 -0.4064)
			(stroke
				(width 0.1524)
				(type default)
			)
			(layer "B.SilkS")
		)
		(fp_line
			(start -0.7874 0.4064)
			(end 0.7874 0.4064)
			(stroke
				(width 0.1524)
				(type default)
			)
			(layer "B.SilkS")
		)
		(fp_line
			(start 0.67945 -0.305054)
			(end 0.12065 -0.305054)
			(stroke
				(width 0.1)
				(type default)
			)
			(layer "B.Fab")
		)
		(fp_line
			(start 0.12065 -0.305054)
			(end 0.12065 -0.2794)
			(stroke
				(width 0.1)
				(type default)
			)
			(layer "B.Fab")
		)
		(fp_line
			(start -0.12065 -0.3048)
			(end -0.67945 -0.3048)
			(stroke
				(width 0.1)
				(type default)
			)
			(layer "B.Fab")
		)
		(fp_line
			(start -0.67945 -0.3048)
			(end -0.67945 0.3048)
			(stroke
				(width 0.1)
				(type default)
			)
			(layer "B.Fab")
		)
		(fp_line
			(start 0.12065 -0.2794)
			(end -0.12065 -0.2794)
			(stroke
				(width 0.1)
				(type default)
			)
			(layer "B.Fab")
		)
		(fp_line
			(start -0.12065 -0.2794)
			(end -0.12065 -0.3048)
			(stroke
				(width 0.1)
				(type default)
			)
			(layer "B.Fab")
		)
		(fp_line
			(start 0.12065 0.2794)
			(end 0.12065 0.3048)
			(stroke
				(width 0.1)
				(type default)
			)
			(layer "B.Fab")
		)
		(fp_line
			(start -0.120396 0.2794)
			(end 0.12065 0.2794)
			(stroke
				(width 0.1)
				(type default)
			)
			(layer "B.Fab")
		)
		(fp_line
			(start 0.67945 0.3048)
			(end 0.67945 -0.305054)
			(stroke
				(width 0.1)
				(type default)
			)
			(layer "B.Fab")
		)
		(fp_line
			(start 0.12065 0.3048)
			(end 0.67945 0.3048)
			(stroke
				(width 0.1)
				(type default)
			)
			(layer "B.Fab")
		)
		(fp_line
			(start -0.120396 0.3048)
			(end -0.120396 0.2794)
			(stroke
				(width 0.1)
				(type default)
			)
			(layer "B.Fab")
		)
		(fp_line
			(start -0.67945 0.3048)
			(end -0.120396 0.3048)
			(stroke
				(width 0.1)
				(type default)
			)
			(layer "B.Fab")
		)
		(pad "1" smd circle
			(at 0.40005 0 270)
			(size 0 0)
			(layers "B.Cu" "B.Mask" "B.Paste")
			(net "P1V2_STBY_MVDD_CK")
		)
		(pad "2" smd circle
			(at -0.40005 0 270)
			(size 0 0)
			(layers "B.Cu" "B.Mask" "B.Paste")
			(net "GND")
		)
	)
)
